(kicad_pcb
	(version 20260206)
	(generator "pcbnew")
	(generator_version "10.0")
	(general
		(thickness 1.6)
		(legacy_teardrops no)
	)
	(paper "A4")
	(title_block
		(title "v1-chassis-manager — T6M_CM_d_v01_1031_1645.brd")
		(comment 1 "Open CloudServer (Microsoft) / footprints 271-280 of 2512")
	)
	(layers
		(0 "F.Cu" signal "TOP")
		(4 "In1.Cu" signal "GND1")
		(6 "In2.Cu" signal "IN1")
		(8 "In3.Cu" signal "VCC1")
		(10 "In4.Cu" signal "VCC2")
		(12 "In5.Cu" signal "GND2")
		(14 "In6.Cu" signal "IN2")
		(16 "In7.Cu" signal "IN3")
		(18 "In8.Cu" signal "GND3")
		(2 "B.Cu" signal "BOTTOM")
		(9 "F.Adhes" user "F.Adhesive")
		(11 "B.Adhes" user "B.Adhesive")
		(13 "F.Paste" user "Package Geometry/Pastemask Top")
		(15 "B.Paste" user "Package Geometry/Pastemask Bottom")
		(5 "F.SilkS" user "Ref Des/Silkscreen Top")
		(7 "B.SilkS" user "Ref Des/Silkscreen Bottom")
		(1 "F.Mask" user "Board Geometry/Soldermask Top")
		(3 "B.Mask" user "Board Geometry/Soldermask Bottom")
		(17 "Dwgs.User" user "User.Drawings")
		(19 "Cmts.User" user "User.Comments")
		(21 "Eco1.User" user "User.Eco1")
		(23 "Eco2.User" user "User.Eco2")
		(25 "Edge.Cuts" user "Board Geometry/Outline")
		(27 "Margin" user)
		(31 "F.CrtYd" user "Package Geometry/Place Bound Top")
		(29 "B.CrtYd" user "Package Geometry/Place Bound Bottom")
		(35 "F.Fab" user "Ref Des/Assembly Top")
		(33 "B.Fab" user "Ref Des/Assembly Bottom")
	)
	(footprint ""
		(layer "F.Cu")
		(at 23.847298 -113.015522 180)
		(property "Reference" "PC67"
			(at -2.939542 -2.669794 0)
			(unlocked yes)
			(layer "F.SilkS")
			(effects
				(font
					(size 0.7874 0.5842)
					(thickness 0.1524)
				)
				(justify left)
			)
		)
		(property "Value" ""
			(at 0 0 180)
			(layer "F.Fab")
			(effects
				(font
					(size 1.27 1.27)
				)
			)
		)
		(duplicate_pad_numbers_are_jumpers no)
		(fp_line
			(start 1.905 0.8636)
			(end -1.905 0.8636)
			(stroke
				(width 0.1524)
				(type default)
			)
			(layer "F.SilkS")
		)
		(fp_line
			(start 1.905 -0.8636)
			(end 1.905 0.8636)
			(stroke
				(width 0.1524)
				(type default)
			)
			(layer "F.SilkS")
		)
		(fp_line
			(start 0 0.8382)
			(end 0 -0.8382)
			(stroke
				(width 0.1524)
				(type default)
			)
			(layer "F.SilkS")
		)
		(fp_line
			(start -1.905 0.8636)
			(end -1.905 -0.8636)
			(stroke
				(width 0.1524)
				(type default)
			)
			(layer "F.SilkS")
		)
		(fp_line
			(start -1.905 -0.8636)
			(end 1.905 -0.8636)
			(stroke
				(width 0.1524)
				(type default)
			)
			(layer "F.SilkS")
		)
		(fp_rect
			(start -1.524 0.7366)
			(end 1.524 -0.7366)
			(stroke
				(width 0)
				(type default)
			)
			(fill no)
			(layer "F.CrtYd")
		)
		(pad "1" smd rect
			(at 0.94996 0 180)
			(size 1.1176 1.3716)
			(layers "F.Cu" "F.Mask" "F.Paste")
			(net "P1V05_NODE1")
		)
		(pad "2" smd rect
			(at -0.94996 0 180)
			(size 1.1176 1.3716)
			(layers "F.Cu" "F.Mask" "F.Paste")
			(net "GND")
		)
	)
	(footprint ""
		(layer "F.Cu")
		(at 44.254166 -121.35866)
		(property "Reference" "C225"
			(at -3.842766 -0.000508 0)
			(unlocked yes)
			(layer "F.SilkS")
			(effects
				(font
					(size 0.7874 0.5842)
					(thickness 0.1524)
				)
				(justify left)
			)
		)
		(property "Value" ""
			(at 0 0 0)
			(layer "F.Fab")
			(effects
				(font
					(size 1.27 1.27)
				)
			)
		)
		(duplicate_pad_numbers_are_jumpers no)
		(fp_line
			(start -0.7874 -0.4064)
			(end 0.7874 -0.4064)
			(stroke
				(width 0.1524)
				(type default)
			)
			(layer "F.SilkS")
		)
		(fp_line
			(start -0.7874 0.4064)
			(end -0.7874 -0.4064)
			(stroke
				(width 0.1524)
				(type default)
			)
			(layer "F.SilkS")
		)
		(fp_line
			(start 0 0.381)
			(end 0 -0.381)
			(stroke
				(width 0.1524)
				(type default)
			)
			(layer "F.SilkS")
		)
		(fp_line
			(start 0.7874 -0.4064)
			(end 0.7874 0.4064)
			(stroke
				(width 0.1524)
				(type default)
			)
			(layer "F.SilkS")
		)
		(fp_line
			(start 0.7874 0.4064)
			(end -0.7874 0.4064)
			(stroke
				(width 0.1524)
				(type default)
			)
			(layer "F.SilkS")
		)
		(fp_poly
			(pts
				(xy -0.5334 0.254) (xy -0.635 0.254) (xy -0.635 0.2286) (xy -0.635 -0.254) (xy -0.5334 -0.254) (xy -0.5334 -0.2794)
				(xy 0.5334 -0.2794) (xy 0.5334 -0.254) (xy 0.635 -0.254) (xy 0.635 0.254) (xy 0.5334 0.254) (xy 0.5334 0.2794)
				(xy -0.508 0.2794) (xy -0.5334 0.2794)
			)
			(stroke
				(width 0)
				(type default)
			)
			(fill no)
			(layer "F.CrtYd")
		)
		(pad "1" smd rect
			(at 0.40005 0)
			(size 0.4572 0.508)
			(layers "F.Cu" "F.Mask" "F.Paste")
			(net "GND")
		)
		(pad "2" smd rect
			(at -0.40005 0)
			(size 0.4572 0.508)
			(layers "F.Cu" "F.Mask" "F.Paste")
			(net "P3V3_NODE1")
		)
	)
	(footprint ""
		(layer "F.Cu")
		(at 100.481638 -181.315106 -90)
		(property "Reference" "U131"
			(at 75.997816 -85.36686 0)
			(unlocked yes)
			(layer "F.SilkS")
			(effects
				(font
					(size 0.7874 0.5842)
					(thickness 0.1524)
				)
			)
		)
		(property "Value" ""
			(at 0 0 270)
			(layer "F.Fab")
			(effects
				(font
					(size 1.27 1.27)
				)
			)
		)
		(duplicate_pad_numbers_are_jumpers no)
		(fp_line
			(start -1.100074 1.3462)
			(end -1.100074 -1.3462)
			(stroke
				(width 0.1524)
				(type default)
			)
			(layer "F.SilkS")
		)
		(fp_line
			(start 1.100074 1.3462)
			(end -1.100074 1.3462)
			(stroke
				(width 0.1524)
				(type default)
			)
			(layer "F.SilkS")
		)
		(fp_line
			(start -1.100074 -1.3462)
			(end 1.100074 -1.3462)
			(stroke
				(width 0.1524)
				(type default)
			)
			(layer "F.SilkS")
		)
		(fp_line
			(start 1.100074 -1.3462)
			(end 1.100074 1.3462)
			(stroke
				(width 0.1524)
				(type default)
			)
			(layer "F.SilkS")
		)
		(fp_poly
			(pts
				(xy -1.256538 0.9906) (xy -2.018538 0.6096) (xy -2.018538 1.3716)
			)
			(stroke
				(width 0)
				(type default)
			)
			(fill yes)
			(layer "F.SilkS")
		)
		(fp_poly
			(pts
				(xy -0.8636 1.2192) (xy -0.8636 0.6858) (xy -1.1176 0.6858) (xy -1.1176 -0.6858) (xy -0.8636 -0.6858)
				(xy -0.8636 -1.2192) (xy 0.8636 -1.2192) (xy 0.8636 -0.6858) (xy 1.1176 -0.6858) (xy 1.1176 0.6858)
				(xy 0.8636 0.6858) (xy 0.8636 1.2192)
			)
			(stroke
				(width 0)
				(type default)
			)
			(fill no)
			(layer "F.CrtYd")
		)
		(pad "1" smd rect
			(at -0.649986 0.94996 270)
			(size 0.4064 0.508)
			(layers "F.Cu" "F.Mask" "F.Paste")
			(net "ATTENTION_LED_N")
		)
		(pad "2" smd rect
			(at 0 0.94996 270)
			(size 0.4064 0.508)
			(layers "F.Cu" "F.Mask" "F.Paste")
			(net "GND")
		)
		(pad "3" smd rect
			(at 0.649986 0.94996 270)
			(size 0.4064 0.508)
			(layers "F.Cu" "F.Mask" "F.Paste")
			(net "CM_STATUS_LED_N")
		)
		(pad "4" smd rect
			(at 0.649986 -0.94996 270)
			(size 0.4064 0.508)
			(layers "F.Cu" "F.Mask" "F.Paste")
			(net "CM_STATUS_LED_R")
		)
		(pad "5" smd rect
			(at 0 -0.94996 270)
			(size 0.4064 0.508)
			(layers "F.Cu" "F.Mask" "F.Paste")
			(net "P3V3_NODE1")
		)
		(pad "6" smd rect
			(at -0.649986 -0.94996 270)
			(size 0.4064 0.508)
			(layers "F.Cu" "F.Mask" "F.Paste")
			(net "ATTENTION_LED_R")
		)
	)
	(footprint ""
		(layer "F.Cu")
		(at 32.920178 -175.459898 90)
		(property "Reference" "C779"
			(at -10.516108 -3.729228 90)
			(unlocked yes)
			(layer "F.SilkS")
			(effects
				(font
					(size 0.7874 0.5842)
					(thickness 0.1524)
				)
				(justify left)
			)
		)
		(property "Value" ""
			(at 0 0 90)
			(layer "F.Fab")
			(effects
				(font
					(size 1.27 1.27)
				)
			)
		)
		(duplicate_pad_numbers_are_jumpers no)
		(fp_line
			(start 0.7874 -0.4064)
			(end 0.7874 0.4064)
			(stroke
				(width 0.1524)
				(type default)
			)
			(layer "F.SilkS")
		)
		(fp_line
			(start -0.7874 -0.4064)
			(end 0.7874 -0.4064)
			(stroke
				(width 0.1524)
				(type default)
			)
			(layer "F.SilkS")
		)
		(fp_line
			(start 0 0.381)
			(end 0 -0.381)
			(stroke
				(width 0.1524)
				(type default)
			)
			(layer "F.SilkS")
		)
		(fp_line
			(start 0.7874 0.4064)
			(end -0.7874 0.4064)
			(stroke
				(width 0.1524)
				(type default)
			)
			(layer "F.SilkS")
		)
		(fp_line
			(start -0.7874 0.4064)
			(end -0.7874 -0.4064)
			(stroke
				(width 0.1524)
				(type default)
			)
			(layer "F.SilkS")
		)
		(fp_poly
			(pts
				(xy -0.5334 0.254) (xy -0.635 0.254) (xy -0.635 0.2286) (xy -0.635 -0.254) (xy -0.5334 -0.254) (xy -0.5334 -0.2794)
				(xy 0.5334 -0.2794) (xy 0.5334 -0.254) (xy 0.635 -0.254) (xy 0.635 0.254) (xy 0.5334 0.254) (xy 0.5334 0.2794)
				(xy -0.508 0.2794) (xy -0.5334 0.2794)
			)
			(stroke
				(width 0)
				(type default)
			)
			(fill no)
			(layer "F.CrtYd")
		)
		(pad "1" smd rect
			(at 0.40005 0 90)
			(size 0.4572 0.508)
			(layers "F.Cu" "F.Mask" "F.Paste")
			(net "VR_HSC_NODE1_GATE_R")
		)
		(pad "2" smd rect
			(at -0.40005 0 90)
			(size 0.4572 0.508)
			(layers "F.Cu" "F.Mask" "F.Paste")
			(net "GND")
		)
	)
	(footprint ""
		(layer "F.Cu")
		(at 149.33676 -188.126624 -90)
		(property "Reference" "R987"
			(at -5.519674 2.681732 90)
			(unlocked yes)
			(layer "F.SilkS")
			(effects
				(font
					(size 0.7874 0.5842)
					(thickness 0.1524)
				)
				(justify left)
			)
		)
		(property "Value" ""
			(at 0 0 270)
			(layer "F.Fab")
			(effects
				(font
					(size 1.27 1.27)
				)
			)
		)
		(duplicate_pad_numbers_are_jumpers no)
		(fp_line
			(start -0.7874 0.4064)
			(end -0.7874 -0.4064)
			(stroke
				(width 0.1524)
				(type default)
			)
			(layer "F.SilkS")
		)
		(fp_line
			(start 0.7874 0.4064)
			(end -0.7874 0.4064)
			(stroke
				(width 0.1524)
				(type default)
			)
			(layer "F.SilkS")
		)
		(fp_line
			(start -0.7874 -0.4064)
			(end 0.7874 -0.4064)
			(stroke
				(width 0.1524)
				(type default)
			)
			(layer "F.SilkS")
		)
		(fp_line
			(start 0.7874 -0.4064)
			(end 0.7874 0.4064)
			(stroke
				(width 0.1524)
				(type default)
			)
			(layer "F.SilkS")
		)
		(fp_poly
			(pts
				(xy -0.508 0.2794) (xy -0.508 0.2286) (xy -0.635 0.2286) (xy -0.635 -0.254) (xy -0.5334 -0.254)
				(xy -0.5334 -0.2794) (xy 0.5334 -0.2794) (xy 0.5334 -0.254) (xy 0.635 -0.254) (xy 0.635 0.254) (xy 0.5334 0.254)
				(xy 0.5334 0.2794)
			)
			(stroke
				(width 0)
				(type default)
			)
			(fill no)
			(layer "F.CrtYd")
		)
		(pad "1" smd rect
			(at 0.40005 0 270)
			(size 0.4572 0.508)
			(layers "F.Cu" "F.Mask" "F.Paste")
			(net "UART_T12_NODE2_RXD")
		)
		(pad "2" smd rect
			(at -0.40005 0 270)
			(size 0.4572 0.508)
			(layers "F.Cu" "F.Mask" "F.Paste")
			(net "UART_T12_NODE2_RXD_R")
		)
	)
	(footprint ""
		(layer "F.Cu")
		(at 95.048578 -120.637046 90)
		(property "Reference" "C1122"
			(at 0.577342 0.760222 0)
			(unlocked yes)
			(layer "F.SilkS")
			(effects
				(font
					(size 0.7874 0.5842)
					(thickness 0.1524)
				)
				(justify left)
			)
		)
		(property "Value" ""
			(at 0 0 90)
			(layer "F.Fab")
			(effects
				(font
					(size 1.27 1.27)
				)
			)
		)
		(duplicate_pad_numbers_are_jumpers no)
		(fp_line
			(start 0.7874 -0.4064)
			(end 0.7874 0.4064)
			(stroke
				(width 0.1524)
				(type default)
			)
			(layer "F.SilkS")
		)
		(fp_line
			(start -0.7874 -0.4064)
			(end 0.7874 -0.4064)
			(stroke
				(width 0.1524)
				(type default)
			)
			(layer "F.SilkS")
		)
		(fp_line
			(start 0 0.381)
			(end 0 -0.381)
			(stroke
				(width 0.1524)
				(type default)
			)
			(layer "F.SilkS")
		)
		(fp_line
			(start 0.7874 0.4064)
			(end -0.7874 0.4064)
			(stroke
				(width 0.1524)
				(type default)
			)
			(layer "F.SilkS")
		)
		(fp_line
			(start -0.7874 0.4064)
			(end -0.7874 -0.4064)
			(stroke
				(width 0.1524)
				(type default)
			)
			(layer "F.SilkS")
		)
		(fp_poly
			(pts
				(xy -0.5334 0.254) (xy -0.635 0.254) (xy -0.635 0.2286) (xy -0.635 -0.254) (xy -0.5334 -0.254) (xy -0.5334 -0.2794)
				(xy 0.5334 -0.2794) (xy 0.5334 -0.254) (xy 0.635 -0.254) (xy 0.635 0.254) (xy 0.5334 0.254) (xy 0.5334 0.2794)
				(xy -0.508 0.2794) (xy -0.5334 0.2794)
			)
			(stroke
				(width 0)
				(type default)
			)
			(fill no)
			(layer "F.CrtYd")
		)
		(pad "1" smd rect
			(at 0.40005 0 90)
			(size 0.4572 0.508)
			(layers "F.Cu" "F.Mask" "F.Paste")
			(net "P3V3_NODE1")
		)
		(pad "2" smd rect
			(at -0.40005 0 90)
			(size 0.4572 0.508)
			(layers "F.Cu" "F.Mask" "F.Paste")
			(net "GND")
		)
	)
	(footprint ""
		(layer "F.Cu")
		(at 116.18976 -188.126624 -90)
		(property "Reference" "R991"
			(at -4.885182 -0.369062 90)
			(unlocked yes)
			(layer "F.SilkS")
			(effects
				(font
					(size 0.7874 0.5842)
					(thickness 0.1524)
				)
				(justify left)
			)
		)
		(property "Value" ""
			(at 0 0 270)
			(layer "F.Fab")
			(effects
				(font
					(size 1.27 1.27)
				)
			)
		)
		(duplicate_pad_numbers_are_jumpers no)
		(fp_line
			(start -0.7874 0.4064)
			(end -0.7874 -0.4064)
			(stroke
				(width 0.1524)
				(type default)
			)
			(layer "F.SilkS")
		)
		(fp_line
			(start 0.7874 0.4064)
			(end -0.7874 0.4064)
			(stroke
				(width 0.1524)
				(type default)
			)
			(layer "F.SilkS")
		)
		(fp_line
			(start -0.7874 -0.4064)
			(end 0.7874 -0.4064)
			(stroke
				(width 0.1524)
				(type default)
			)
			(layer "F.SilkS")
		)
		(fp_line
			(start 0.7874 -0.4064)
			(end 0.7874 0.4064)
			(stroke
				(width 0.1524)
				(type default)
			)
			(layer "F.SilkS")
		)
		(fp_poly
			(pts
				(xy -0.508 0.2794) (xy -0.508 0.2286) (xy -0.635 0.2286) (xy -0.635 -0.254) (xy -0.5334 -0.254)
				(xy -0.5334 -0.2794) (xy 0.5334 -0.2794) (xy 0.5334 -0.254) (xy 0.635 -0.254) (xy 0.635 0.254) (xy 0.5334 0.254)
				(xy 0.5334 0.2794)
			)
			(stroke
				(width 0)
				(type default)
			)
			(fill no)
			(layer "F.CrtYd")
		)
		(pad "1" smd rect
			(at 0.40005 0 270)
			(size 0.4572 0.508)
			(layers "F.Cu" "F.Mask" "F.Paste")
			(net "UART_T8_NODE3_RXD")
		)
		(pad "2" smd rect
			(at -0.40005 0 270)
			(size 0.4572 0.508)
			(layers "F.Cu" "F.Mask" "F.Paste")
			(net "UART_T8_NODE3_RXD_R")
		)
	)
	(footprint ""
		(layer "F.Cu")
		(at 70.1548 -101.397562 180)
		(property "Reference" "R1091"
			(at 1.169416 3.10642 0)
			(unlocked yes)
			(layer "F.SilkS")
			(effects
				(font
					(size 0.7874 0.5842)
					(thickness 0.1524)
				)
				(justify left)
			)
		)
		(property "Value" ""
			(at 0 0 180)
			(layer "F.Fab")
			(effects
				(font
					(size 1.27 1.27)
				)
			)
		)
		(duplicate_pad_numbers_are_jumpers no)
		(fp_line
			(start 0.7874 0.4064)
			(end -0.7874 0.4064)
			(stroke
				(width 0.1524)
				(type default)
			)
			(layer "F.SilkS")
		)
		(fp_line
			(start 0.7874 -0.4064)
			(end 0.7874 0.4064)
			(stroke
				(width 0.1524)
				(type default)
			)
			(layer "F.SilkS")
		)
		(fp_line
			(start -0.7874 0.4064)
			(end -0.7874 -0.4064)
			(stroke
				(width 0.1524)
				(type default)
			)
			(layer "F.SilkS")
		)
		(fp_line
			(start -0.7874 -0.4064)
			(end 0.7874 -0.4064)
			(stroke
				(width 0.1524)
				(type default)
			)
			(layer "F.SilkS")
		)
		(fp_poly
			(pts
				(xy -0.508 0.2794) (xy -0.508 0.2286) (xy -0.635 0.2286) (xy -0.635 -0.254) (xy -0.5334 -0.254)
				(xy -0.5334 -0.2794) (xy 0.5334 -0.2794) (xy 0.5334 -0.254) (xy 0.635 -0.254) (xy 0.635 0.254) (xy 0.5334 0.254)
				(xy 0.5334 0.2794)
			)
			(stroke
				(width 0)
				(type default)
			)
			(fill no)
			(layer "F.CrtYd")
		)
		(pad "1" smd rect
			(at 0.40005 0 180)
			(size 0.4572 0.508)
			(layers "F.Cu" "F.Mask" "F.Paste")
			(net "FM_CPLD_NODE1_P1V8_SUS_EN")
		)
		(pad "2" smd rect
			(at -0.40005 0 180)
			(size 0.4572 0.508)
			(layers "F.Cu" "F.Mask" "F.Paste")
			(net "P3V3_STB_NODE1")
		)
	)
	(footprint ""
		(layer "F.Cu")
		(at 124.85116 -188.126624 90)
		(property "Reference" "C626"
			(at 4.949444 -0.396748 90)
			(unlocked yes)
			(layer "F.SilkS")
			(effects
				(font
					(size 0.7874 0.5842)
					(thickness 0.1524)
				)
				(justify left)
			)
		)
		(property "Value" ""
			(at 0 0 90)
			(layer "F.Fab")
			(effects
				(font
					(size 1.27 1.27)
				)
			)
		)
		(duplicate_pad_numbers_are_jumpers no)
		(fp_line
			(start 0.7874 -0.4064)
			(end 0.7874 0.4064)
			(stroke
				(width 0.1524)
				(type default)
			)
			(layer "F.SilkS")
		)
		(fp_line
			(start -0.7874 -0.4064)
			(end 0.7874 -0.4064)
			(stroke
				(width 0.1524)
				(type default)
			)
			(layer "F.SilkS")
		)
		(fp_line
			(start 0 0.381)
			(end 0 -0.381)
			(stroke
				(width 0.1524)
				(type default)
			)
			(layer "F.SilkS")
		)
		(fp_line
			(start 0.7874 0.4064)
			(end -0.7874 0.4064)
			(stroke
				(width 0.1524)
				(type default)
			)
			(layer "F.SilkS")
		)
		(fp_line
			(start -0.7874 0.4064)
			(end -0.7874 -0.4064)
			(stroke
				(width 0.1524)
				(type default)
			)
			(layer "F.SilkS")
		)
		(fp_poly
			(pts
				(xy -0.5334 0.254) (xy -0.635 0.254) (xy -0.635 0.2286) (xy -0.635 -0.254) (xy -0.5334 -0.254) (xy -0.5334 -0.2794)
				(xy 0.5334 -0.2794) (xy 0.5334 -0.254) (xy 0.635 -0.254) (xy 0.635 0.254) (xy 0.5334 0.254) (xy 0.5334 0.2794)
				(xy -0.508 0.2794) (xy -0.5334 0.2794)
			)
			(stroke
				(width 0)
				(type default)
			)
			(fill no)
			(layer "F.CrtYd")
		)
		(pad "1" smd rect
			(at 0.40005 0 90)
			(size 0.4572 0.508)
			(layers "F.Cu" "F.Mask" "F.Paste")
			(net "T8_NODE2_EN_R")
		)
		(pad "2" smd rect
			(at -0.40005 0 90)
			(size 0.4572 0.508)
			(layers "F.Cu" "F.Mask" "F.Paste")
			(net "GND")
		)
	)
	(footprint ""
		(layer "F.Cu")
		(at 81.56194 -84.438744 -90)
		(property "Reference" "R64"
			(at 17.669764 -1.85166 90)
			(unlocked yes)
			(layer "F.SilkS")
			(effects
				(font
					(size 0.7874 0.5842)
					(thickness 0.1524)
				)
				(justify left)
			)
		)
		(property "Value" ""
			(at 0 0 270)
			(layer "F.Fab")
			(effects
				(font
					(size 1.27 1.27)
				)
			)
		)
		(duplicate_pad_numbers_are_jumpers no)
		(fp_line
			(start -0.7874 0.406146)
			(end -0.7874 -0.406146)
			(stroke
				(width 0.1524)
				(type default)
			)
			(layer "F.SilkS")
		)
		(fp_line
			(start 0.7874 0.406146)
			(end -0.7874 0.406146)
			(stroke
				(width 0.1524)
				(type default)
			)
			(layer "F.SilkS")
		)
		(fp_line
			(start -0.7874 -0.406146)
			(end 0.7874 -0.406146)
			(stroke
				(width 0.1524)
				(type default)
			)
			(layer "F.SilkS")
		)
		(fp_line
			(start 0.7874 -0.406146)
			(end 0.7874 0.406146)
			(stroke
				(width 0.1524)
				(type default)
			)
			(layer "F.SilkS")
		)
		(fp_poly
			(pts
				(xy -0.508 0.2794) (xy -0.508 0.2286) (xy -0.635 0.2286) (xy -0.635 -0.254) (xy -0.5334 -0.254)
				(xy -0.5334 -0.2794) (xy 0.5334 -0.2794) (xy 0.5334 -0.254) (xy 0.635 -0.254) (xy 0.635 0.254) (xy 0.5334 0.254)
				(xy 0.5334 0.2794)
			)
			(stroke
				(width 0)
				(type default)
			)
			(fill no)
			(layer "F.CrtYd")
		)
		(pad "1" smd rect
			(at 0.40005 0 270)
			(size 0.4572 0.508)
			(layers "F.Cu" "F.Mask" "F.Paste")
			(net "XTAL_CPU_NODE1_X1PAD")
		)
		(pad "2" smd rect
			(at -0.40005 0 270)
			(size 0.4572 0.508)
			(layers "F.Cu" "F.Mask" "F.Paste")
			(net "XTAL_CPU_NODE1_X2PAD")
		)
	)
)
